# T6G (Grand Teton) — schematic netlist excerpt (pin names and nets, part order shuffled) for the footprints in the layout excerpt that follows; sources: Cadence DE-HDL packaged netlist, KiCad conversion of 04192023_DAF0TMB3IC0_F0TG_MB_C_brd_V02_OCP.brd

PR95  Q_RES  5.6 1% CHIP  pkg 0402LF  page 203 : A = SW_PVDDCR_CPU1_P0_BOOT5 ; B = SW_PVDDCR_CPU1_P0_BOOT5_R
R3622  Q_RES  4.7K 1% CHIP  pkg 0402LF  page 237 : A = P3V3_AUX ; B = INA230_5_A0

(kicad_pcb
	(version 20260206)
	(generator "pcbnew")
	(generator_version "10.0")
	(general
		(thickness 1.6)
		(legacy_teardrops no)
	)
	(paper "A4")
	(title_block
		(title "04192023_DAF0TMB3IC0_F0TG_MB_C_brd_V02_OCP.brd")
		(comment 1 "Grand Teton / footprints 1183-1184 of 8354")
	)
	(layers
		(0 "F.Cu" signal "TOP")
		(4 "In1.Cu" signal "GND")
		(6 "In2.Cu" signal "IN1")
		(8 "In3.Cu" signal "GND1")
		(10 "In4.Cu" signal "IN2")
		(12 "In5.Cu" signal "GND2")
		(14 "In6.Cu" signal "IN3")
		(16 "In7.Cu" signal "GND3")
		(18 "In8.Cu" signal "VCC")
		(20 "In9.Cu" signal "VCC1")
		(22 "In10.Cu" signal "GND4")
		(24 "In11.Cu" signal "IN4")
		(26 "In12.Cu" signal "GND5")
		(28 "In13.Cu" signal "IN5")
		(30 "In14.Cu" signal "GND6")
		(32 "In15.Cu" signal "IN6")
		(34 "In16.Cu" signal "GND7")
		(2 "B.Cu" signal "BOTTOM")
		(9 "F.Adhes" user "F.Adhesive")
		(11 "B.Adhes" user "B.Adhesive")
		(13 "F.Paste" user "Package Geometry/Pastemask Top")
		(15 "B.Paste" user "Package Geometry/Pastemask Bottom")
		(5 "F.SilkS" user "Ref Des/Silkscreen Top")
		(7 "B.SilkS" user "Ref Des/Silkscreen Bottom")
		(1 "F.Mask" user "Board Geometry/Soldermask Top")
		(3 "B.Mask" user "Board Geometry/Soldermask Bottom")
		(17 "Dwgs.User" user "User.Drawings")
		(19 "Cmts.User" user "User.Comments")
		(21 "Eco1.User" user "User.Eco1")
		(23 "Eco2.User" user "User.Eco2")
		(25 "Edge.Cuts" user "Board Geometry/Outline")
		(27 "Margin" user)
		(31 "F.CrtYd" user "Package Geometry/Place Bound Top")
		(29 "B.CrtYd" user "Package Geometry/Place Bound Bottom")
		(35 "F.Fab" user "Ref Des/Assembly Top")
		(33 "B.Fab" user "Ref Des/Assembly Bottom")
	)
	(footprint ""
		(layer "F.Cu")
		(at 344.149426 -339.676232 90)
		(property "Reference" "PR95"
			(at 0 0 90)
			(layer "F.SilkS")
			(hide yes)
			(effects
				(font
					(size 1.27 1.27)
				)
			)
		)
		(property "Value" ""
			(at 0 0 90)
			(layer "F.Fab")
			(effects
				(font
					(size 1.27 1.27)
				)
			)
		)
		(duplicate_pad_numbers_are_jumpers no)
		(fp_line
			(start 0.7874 -0.4064)
			(end 0.7874 0.4064)
			(stroke
				(width 0.1524)
				(type default)
			)
			(layer "F.SilkS")
		)
		(fp_line
			(start -0.7874 -0.4064)
			(end 0.7874 -0.4064)
			(stroke
				(width 0.1524)
				(type default)
			)
			(layer "F.SilkS")
		)
		(fp_line
			(start 0.7874 0.4064)
			(end -0.7874 0.4064)
			(stroke
				(width 0.1524)
				(type default)
			)
			(layer "F.SilkS")
		)
		(fp_line
			(start -0.7874 0.4064)
			(end -0.7874 -0.4064)
			(stroke
				(width 0.1524)
				(type default)
			)
			(layer "F.SilkS")
		)
		(fp_line
			(start -0.12065 -0.305054)
			(end -0.12065 -0.2794)
			(stroke
				(width 0.1)
				(type default)
			)
			(layer "F.Fab")
		)
		(fp_line
			(start -0.67945 -0.305054)
			(end -0.12065 -0.305054)
			(stroke
				(width 0.1)
				(type default)
			)
			(layer "F.Fab")
		)
		(fp_line
			(start 0.67945 -0.3048)
			(end 0.67945 0.3048)
			(stroke
				(width 0.1)
				(type default)
			)
			(layer "F.Fab")
		)
		(fp_line
			(start 0.12065 -0.3048)
			(end 0.67945 -0.3048)
			(stroke
				(width 0.1)
				(type default)
			)
			(layer "F.Fab")
		)
		(fp_line
			(start 0.12065 -0.2794)
			(end 0.12065 -0.3048)
			(stroke
				(width 0.1)
				(type default)
			)
			(layer "F.Fab")
		)
		(fp_line
			(start -0.12065 -0.2794)
			(end 0.12065 -0.2794)
			(stroke
				(width 0.1)
				(type default)
			)
			(layer "F.Fab")
		)
		(fp_line
			(start 0.120396 0.2794)
			(end -0.12065 0.2794)
			(stroke
				(width 0.1)
				(type default)
			)
			(layer "F.Fab")
		)
		(fp_line
			(start -0.12065 0.2794)
			(end -0.12065 0.3048)
			(stroke
				(width 0.1)
				(type default)
			)
			(layer "F.Fab")
		)
		(fp_line
			(start 0.67945 0.3048)
			(end 0.120396 0.3048)
			(stroke
				(width 0.1)
				(type default)
			)
			(layer "F.Fab")
		)
		(fp_line
			(start 0.120396 0.3048)
			(end 0.120396 0.2794)
			(stroke
				(width 0.1)
				(type default)
			)
			(layer "F.Fab")
		)
		(fp_line
			(start -0.12065 0.3048)
			(end -0.67945 0.3048)
			(stroke
				(width 0.1)
				(type default)
			)
			(layer "F.Fab")
		)
		(fp_line
			(start -0.67945 0.3048)
			(end -0.67945 -0.305054)
			(stroke
				(width 0.1)
				(type default)
			)
			(layer "F.Fab")
		)
		(pad "1" smd circle
			(at -0.40005 0 90)
			(size 0 0)
			(layers "F.Cu" "F.Mask" "F.Paste")
			(net "SW_PVDDCR_CPU1_P0_BOOT5")
		)
		(pad "2" smd circle
			(at 0.40005 0 90)
			(size 0 0)
			(layers "F.Cu" "F.Mask" "F.Paste")
			(net "SW_PVDDCR_CPU1_P0_BOOT5_R")
		)
	)
	(footprint ""
		(layer "F.Cu")
		(at 210.086956 -30.276292 90)
		(property "Reference" "R3622"
			(at 0 0 90)
			(layer "F.SilkS")
			(hide yes)
			(effects
				(font
					(size 1.27 1.27)
				)
			)
		)
		(property "Value" ""
			(at 0 0 90)
			(layer "F.Fab")
			(effects
				(font
					(size 1.27 1.27)
				)
			)
		)
		(duplicate_pad_numbers_are_jumpers no)
		(fp_line
			(start 0.7874 -0.4064)
			(end 0.7874 0.4064)
			(stroke
				(width 0.1524)
				(type default)
			)
			(layer "F.SilkS")
		)
		(fp_line
			(start -0.7874 -0.4064)
			(end 0.7874 -0.4064)
			(stroke
				(width 0.1524)
				(type default)
			)
			(layer "F.SilkS")
		)
		(fp_line
			(start 0.7874 0.4064)
			(end -0.7874 0.4064)
			(stroke
				(width 0.1524)
				(type default)
			)
			(layer "F.SilkS")
		)
		(fp_line
			(start -0.7874 0.4064)
			(end -0.7874 -0.4064)
			(stroke
				(width 0.1524)
				(type default)
			)
			(layer "F.SilkS")
		)
		(fp_line
			(start -0.12065 -0.305054)
			(end -0.12065 -0.2794)
			(stroke
				(width 0.1)
				(type default)
			)
			(layer "F.Fab")
		)
		(fp_line
			(start -0.67945 -0.305054)
			(end -0.12065 -0.305054)
			(stroke
				(width 0.1)
				(type default)
			)
			(layer "F.Fab")
		)
		(fp_line
			(start 0.67945 -0.3048)
			(end 0.67945 0.3048)
			(stroke
				(width 0.1)
				(type default)
			)
			(layer "F.Fab")
		)
		(fp_line
			(start 0.12065 -0.3048)
			(end 0.67945 -0.3048)
			(stroke
				(width 0.1)
				(type default)
			)
			(layer "F.Fab")
		)
		(fp_line
			(start 0.12065 -0.2794)
			(end 0.12065 -0.3048)
			(stroke
				(width 0.1)
				(type default)
			)
			(layer "F.Fab")
		)
		(fp_line
			(start -0.12065 -0.2794)
			(end 0.12065 -0.2794)
			(stroke
				(width 0.1)
				(type default)
			)
			(layer "F.Fab")
		)
		(fp_line
			(start 0.120396 0.2794)
			(end -0.12065 0.2794)
			(stroke
				(width 0.1)
				(type default)
			)
			(layer "F.Fab")
		)
		(fp_line
			(start -0.12065 0.2794)
			(end -0.12065 0.3048)
			(stroke
				(width 0.1)
				(type default)
			)
			(layer "F.Fab")
		)
		(fp_line
			(start 0.67945 0.3048)
			(end 0.120396 0.3048)
			(stroke
				(width 0.1)
				(type default)
			)
			(layer "F.Fab")
		)
		(fp_line
			(start 0.120396 0.3048)
			(end 0.120396 0.2794)
			(stroke
				(width 0.1)
				(type default)
			)
			(layer "F.Fab")
		)
		(fp_line
			(start -0.12065 0.3048)
			(end -0.67945 0.3048)
			(stroke
				(width 0.1)
				(type default)
			)
			(layer "F.Fab")
		)
		(fp_line
			(start -0.67945 0.3048)
			(end -0.67945 -0.305054)
			(stroke
				(width 0.1)
				(type default)
			)
			(layer "F.Fab")
		)
		(pad "1" smd circle
			(at -0.40005 0 90)
			(size 0 0)
			(layers "F.Cu" "F.Mask" "F.Paste")
			(net "P3V3_AUX")
		)
		(pad "2" smd circle
			(at 0.40005 0 90)
			(size 0 0)
			(layers "F.Cu" "F.Mask" "F.Paste")
			(net "INA230_5_A0")
		)
	)
)
